(kicad_pcb
	(version 20241229)
	(generator "pcbnew")
	(generator_version "9.0")
	(general
		(thickness 1.6)
		(legacy_teardrops no)
	)
	(paper "A4")
	(title_block
		(title "GMSL Deserializer")
		(date "2025-10-09")
		(rev "1.0.4")
		(company "Antmicro Ltd")
		(comment 1 "www.antmicro.com")
		(comment 9 "footprints 146-147 of 235")
	)
	(layers
		(0 "F.Cu" signal)
		(4 "In1.Cu" power)
		(6 "In2.Cu" power)
		(2 "B.Cu" signal)
		(9 "F.Adhes" user "F.Adhesive")
		(11 "B.Adhes" user "B.Adhesive")
		(13 "F.Paste" user)
		(15 "B.Paste" user)
		(5 "F.SilkS" user "F.Silkscreen")
		(7 "B.SilkS" user "B.Silkscreen")
		(1 "F.Mask" user)
		(3 "B.Mask" user)
		(17 "Dwgs.User" user "User.Drawings")
		(19 "Cmts.User" user "User.Comments")
		(21 "Eco1.User" user "User.Eco1")
		(23 "Eco2.User" user "User.Eco2")
		(25 "Edge.Cuts" user)
		(27 "Margin" user)
		(31 "F.CrtYd" user "F.Courtyard")
		(29 "B.CrtYd" user "B.Courtyard")
		(35 "F.Fab" user)
		(33 "B.Fab" user)
	)
	(footprint "antmicro-footprints:Conn_FFC_WE_68715014x22"
		(layer "F.Cu")
		(at 186.036 73.183 90)
		(property "Reference" "J6"
			(at -14.868 -2.902 90)
			(layer "F.SilkS")
			(effects
				(font
					(size 0.7 0.7)
					(thickness 0.15)
				)
				(justify left bottom)
			)
		)
		(property "Value" "Conn_FFC_WE_68715014522"
			(at 0 4.5 90)
			(layer "F.Fab")
			(effects
				(font
					(size 0.7 0.7)
					(thickness 0.15)
				)
				(justify left bottom)
			)
		)
		(property "Datasheet" "https://www.we-online.com/components/products/datasheet/68715014522.pdf"
			(at 0 0 90)
			(layer "F.Fab")
			(hide yes)
			(effects
				(font
					(size 1.27 1.27)
					(thickness 0.15)
				)
			)
		)
		(property "Description" "FFC connector"
			(at 0 0 90)
			(layer "F.Fab")
			(hide yes)
			(effects
				(font
					(size 1.27 1.27)
					(thickness 0.15)
				)
			)
		)
		(property "Author" "Antmicro"
			(at 259.219 -112.853 0)
			(layer "F.Fab")
			(hide yes)
			(effects
				(font
					(size 1 1)
					(thickness 0.15)
				)
			)
		)
		(property "License" "Apache-2.0"
			(at 259.219 -112.853 0)
			(layer "F.Fab")
			(hide yes)
			(effects
				(font
					(size 1 1)
					(thickness 0.15)
				)
			)
		)
		(property "MPN" "68715014522"
			(at 259.219 -112.853 0)
			(layer "F.Fab")
			(hide yes)
			(effects
				(font
					(size 1 1)
					(thickness 0.15)
				)
			)
		)
		(property "Manufacturer" "Würth Elektronik"
			(at 259.219 -112.853 0)
			(layer "F.Fab")
			(hide yes)
			(effects
				(font
					(size 1 1)
					(thickness 0.15)
				)
			)
		)
		(property "VSD_Class" "Antmicro Dual Camera interface"
			(at 259.219 -112.853 0)
			(layer "F.Fab")
			(hide yes)
			(effects
				(font
					(size 1 1)
					(thickness 0.15)
				)
			)
		)
		(sheetname "/Connectors/")
		(sheetfile "connectors.kicad_sch")
		(attr smd)
		(fp_line
			(start -12.5 -2.976)
			(end 12.499 -2.976)
			(stroke
				(width 0.15)
				(type solid)
			)
			(layer "F.SilkS")
		)
		(fp_line
			(start 15.85 -2.15)
			(end 12.499 -2.15)
			(stroke
				(width 0.15)
				(type solid)
			)
			(layer "F.SilkS")
		)
		(fp_line
			(start 12.499 -2.15)
			(end 12.499 -2.976)
			(stroke
				(width 0.15)
				(type solid)
			)
			(layer "F.SilkS")
		)
		(fp_line
			(start -12.5 -2.15)
			(end -12.5 -2.976)
			(stroke
				(width 0.15)
				(type solid)
			)
			(layer "F.SilkS")
		)
		(fp_line
			(start -15.85 -2.15)
			(end -12.5 -2.15)
			(stroke
				(width 0.15)
				(type solid)
			)
			(layer "F.SilkS")
		)
		(fp_line
			(start 15.85 2.7)
			(end 15.85 -2.15)
			(stroke
				(width 0.15)
				(type solid)
			)
			(layer "F.SilkS")
		)
		(fp_line
			(start 15.85 2.7)
			(end -15.85 2.7)
			(stroke
				(width 0.15)
				(type solid)
			)
			(layer "F.SilkS")
		)
		(fp_line
			(start -15.85 2.7)
			(end -15.85 -2.15)
			(stroke
				(width 0.15)
				(type solid)
			)
			(layer "F.SilkS")
		)
		(fp_circle
			(center -12.9 -2.9)
			(end -12.85 -2.85)
			(stroke
				(width 0.15)
				(type solid)
			)
			(fill yes)
			(layer "F.SilkS")
		)
		(fp_rect
			(start -16.2 -3.25)
			(end 16.2 3.55)
			(stroke
				(width 0.05)
				(type solid)
			)
			(fill no)
			(layer "F.CrtYd")
		)
		(pad "1" smd roundrect
			(at -12.25 -2.15 90)
			(size 0.3 1.2)
			(layers "F.Cu" "F.Mask" "F.Paste")
			(roundrect_rratio 0.25)
			(net 99 "/Connectors/CSI0.D3_N")
			(pintype "passive")
		)
		(pad "2" smd roundrect
			(at -11.75 -2.15 90)
			(size 0.3 1.2)
			(layers "F.Cu" "F.Mask" "F.Paste")
			(roundrect_rratio 0.25)
			(net 100 "/Connectors/CSI0.D3_P")
			(pintype "passive")
		)
		(pad "3" smd roundrect
			(at -11.25 -2.15 90)
			(size 0.3 1.2)
			(layers "F.Cu" "F.Mask" "F.Paste")
			(roundrect_rratio 0.25)
			(net 101 "/Connectors/CSI0.D2_N")
			(pintype "passive")
		)
		(pad "4" smd roundrect
			(at -10.75 -2.15 90)
			(size 0.3 1.2)
			(layers "F.Cu" "F.Mask" "F.Paste")
			(roundrect_rratio 0.25)
			(net 102 "/Connectors/CSI0.D2_P")
			(pintype "passive")
		)
		(pad "5" smd roundrect
			(at -10.25 -2.15 90)
			(size 0.3 1.2)
			(layers "F.Cu" "F.Mask" "F.Paste")
			(roundrect_rratio 0.25)
			(net 89 "/Connectors/CSI0.D1_N")
			(pintype "passive")
		)
		(pad "6" smd roundrect
			(at -9.75 -2.15 90)
			(size 0.3 1.2)
			(layers "F.Cu" "F.Mask" "F.Paste")
			(roundrect_rratio 0.25)
			(net 90 "/Connectors/CSI0.D1_P")
			(pintype "passive")
		)
		(pad "7" smd roundrect
			(at -9.25 -2.15 90)
			(size 0.3 1.2)
			(layers "F.Cu" "F.Mask" "F.Paste")
			(roundrect_rratio 0.25)
			(net 91 "/Connectors/CSI0.D0_N")
			(pintype "passive")
		)
		(pad "8" smd roundrect
			(at -8.75 -2.15 90)
			(size 0.3 1.2)
			(layers "F.Cu" "F.Mask" "F.Paste")
			(roundrect_rratio 0.25)
			(net 92 "/Connectors/CSI0.D0_P")
			(pintype "passive")
		)
		(pad "9" smd roundrect
			(at -8.25 -2.15 90)
			(size 0.3 1.2)
			(layers "F.Cu" "F.Mask" "F.Paste")
			(roundrect_rratio 0.25)
			(net 1 "GND")
			(pintype "passive")
		)
		(pad "10" smd roundrect
			(at -7.75 -2.15 90)
			(size 0.3 1.2)
			(layers "F.Cu" "F.Mask" "F.Paste")
			(roundrect_rratio 0.25)
			(net 103 "/Connectors/CSI0.CLK_N")
			(pintype "passive")
		)
		(pad "11" smd roundrect
			(at -7.25 -2.15 90)
			(size 0.3 1.2)
			(layers "F.Cu" "F.Mask" "F.Paste")
			(roundrect_rratio 0.25)
			(net 104 "/Connectors/CSI0.CLK_P")
			(pintype "passive")
		)
		(pad "12" smd roundrect
			(at -6.75 -2.15 90)
			(size 0.3 1.2)
			(layers "F.Cu" "F.Mask" "F.Paste")
			(roundrect_rratio 0.25)
			(net 1 "GND")
			(pintype "passive")
		)
		(pad "13" smd roundrect
			(at -6.25 -2.15 90)
			(size 0.3 1.2)
			(layers "F.Cu" "F.Mask" "F.Paste")
			(roundrect_rratio 0.25)
			(net 30 "unconnected-(J6-Pad13)")
			(pintype "passive+no_connect")
		)
		(pad "14" smd roundrect
			(at -5.75 -2.15 90)
			(size 0.3 1.2)
			(layers "F.Cu" "F.Mask" "F.Paste")
			(roundrect_rratio 0.25)
			(net 31 "unconnected-(J6-Pad14)")
			(pintype "passive+no_connect")
		)
		(pad "15" smd roundrect
			(at -5.25 -2.15 90)
			(size 0.3 1.2)
			(layers "F.Cu" "F.Mask" "F.Paste")
			(roundrect_rratio 0.25)
			(net 1 "GND")
			(pintype "passive")
		)
		(pad "16" smd roundrect
			(at -4.75 -2.15 90)
			(size 0.3 1.2)
			(layers "F.Cu" "F.Mask" "F.Paste")
			(roundrect_rratio 0.25)
			(net 32 "unconnected-(J6-Pad16)")
			(pintype "passive+no_connect")
		)
		(pad "17" smd roundrect
			(at -4.25 -2.15 90)
			(size 0.3 1.2)
			(layers "F.Cu" "F.Mask" "F.Paste")
			(roundrect_rratio 0.25)
			(net 33 "unconnected-(J6-Pad17)")
			(pintype "passive+no_connect")
		)
		(pad "18" smd roundrect
			(at -3.75 -2.15 90)
			(size 0.3 1.2)
			(layers "F.Cu" "F.Mask" "F.Paste")
			(roundrect_rratio 0.25)
			(net 1 "GND")
			(pintype "passive")
		)
		(pad "19" smd roundrect
			(at -3.25 -2.15 90)
			(size 0.3 1.2)
			(layers "F.Cu" "F.Mask" "F.Paste")
			(roundrect_rratio 0.25)
			(net 105 "/Connectors/CSI1.D3_N")
			(pintype "passive")
		)
		(pad "20" smd roundrect
			(at -2.75 -2.15 90)
			(size 0.3 1.2)
			(layers "F.Cu" "F.Mask" "F.Paste")
			(roundrect_rratio 0.25)
			(net 106 "/Connectors/CSI1.D3_P")
			(pintype "passive")
		)
		(pad "21" smd roundrect
			(at -2.25 -2.15 90)
			(size 0.3 1.2)
			(layers "F.Cu" "F.Mask" "F.Paste")
			(roundrect_rratio 0.25)
			(net 107 "/Connectors/CSI1.D2_N")
			(pintype "passive")
		)
		(pad "22" smd roundrect
			(at -1.75 -2.15 90)
			(size 0.3 1.2)
			(layers "F.Cu" "F.Mask" "F.Paste")
			(roundrect_rratio 0.25)
			(net 108 "/Connectors/CSI1.D2_P")
			(pintype "passive")
		)
		(pad "23" smd roundrect
			(at -1.25 -2.15 90)
			(size 0.3 1.2)
			(layers "F.Cu" "F.Mask" "F.Paste")
			(roundrect_rratio 0.25)
			(net 93 "/Connectors/CSI1.D1_N")
			(pintype "passive")
		)
		(pad "24" smd roundrect
			(at -0.75 -2.15 90)
			(size 0.3 1.2)
			(layers "F.Cu" "F.Mask" "F.Paste")
			(roundrect_rratio 0.25)
			(net 94 "/Connectors/CSI1.D1_P")
			(pintype "passive")
		)
		(pad "25" smd roundrect
			(at -0.25 -2.15 90)
			(size 0.3 1.2)
			(layers "F.Cu" "F.Mask" "F.Paste")
			(roundrect_rratio 0.25)
			(net 95 "/Connectors/CSI1.D0_N")
			(pintype "passive")
		)
		(pad "26" smd roundrect
			(at 0.248 -2.15 90)
			(size 0.3 1.2)
			(layers "F.Cu" "F.Mask" "F.Paste")
			(roundrect_rratio 0.25)
			(net 96 "/Connectors/CSI1.D0_P")
			(pintype "passive")
		)
		(pad "27" smd roundrect
			(at 0.748 -2.15 90)
			(size 0.3 1.2)
			(layers "F.Cu" "F.Mask" "F.Paste")
			(roundrect_rratio 0.25)
			(net 1 "GND")
			(pintype "passive")
		)
		(pad "28" smd roundrect
			(at 1.249 -2.15 90)
			(size 0.3 1.2)
			(layers "F.Cu" "F.Mask" "F.Paste")
			(roundrect_rratio 0.25)
			(net 97 "/Connectors/CSI1.CLK_N")
			(pintype "passive")
		)
		(pad "29" smd roundrect
			(at 1.749 -2.15 90)
			(size 0.3 1.2)
			(layers "F.Cu" "F.Mask" "F.Paste")
			(roundrect_rratio 0.25)
			(net 98 "/Connectors/CSI1.CLK_P")
			(pintype "passive")
		)
		(pad "30" smd roundrect
			(at 2.249 -2.15 90)
			(size 0.3 1.2)
			(layers "F.Cu" "F.Mask" "F.Paste")
			(roundrect_rratio 0.25)
			(net 1 "GND")
			(pintype "passive")
		)
		(pad "31" smd roundrect
			(at 2.749 -2.15 90)
			(size 0.3 1.2)
			(layers "F.Cu" "F.Mask" "F.Paste")
			(roundrect_rratio 0.25)
			(net 34 "unconnected-(J6-Pad31)")
			(pintype "passive+no_connect")
		)
		(pad "32" smd roundrect
			(at 3.249 -2.15 90)
			(size 0.3 1.2)
			(layers "F.Cu" "F.Mask" "F.Paste")
			(roundrect_rratio 0.25)
			(net 35 "Net-(J6-Pad32)")
			(pintype "passive")
		)
		(pad "33" smd roundrect
			(at 3.749 -2.15 90)
			(size 0.3 1.2)
			(layers "F.Cu" "F.Mask" "F.Paste")
			(roundrect_rratio 0.25)
			(net 36 "unconnected-(J6-Pad33)")
			(pintype "passive+no_connect")
		)
		(pad "34" smd roundrect
			(at 4.248 -2.15 90)
			(size 0.3 1.2)
			(layers "F.Cu" "F.Mask" "F.Paste")
			(roundrect_rratio 0.25)
			(net 37 "Net-(J6-Pad34)")
			(pintype "passive")
		)
		(pad "35" smd roundrect
			(at 4.748 -2.15 90)
			(size 0.3 1.2)
			(layers "F.Cu" "F.Mask" "F.Paste")
			(roundrect_rratio 0.25)
			(net 38 "unconnected-(J6-Pad35)")
			(pintype "passive+no_connect")
		)
		(pad "36" smd roundrect
			(at 5.248 -2.15 90)
			(size 0.3 1.2)
			(layers "F.Cu" "F.Mask" "F.Paste")
			(roundrect_rratio 0.25)
			(net 39 "unconnected-(J6-Pad36)")
			(pintype "passive+no_connect")
		)
		(pad "37" smd roundrect
			(at 5.749 -2.15 90)
			(size 0.3 1.2)
			(layers "F.Cu" "F.Mask" "F.Paste")
			(roundrect_rratio 0.25)
			(net 40 "unconnected-(J6-Pad37)")
			(pintype "passive+no_connect")
		)
		(pad "38" smd roundrect
			(at 6.249 -2.15 90)
			(size 0.3 1.2)
			(layers "F.Cu" "F.Mask" "F.Paste")
			(roundrect_rratio 0.25)
			(net 41 "unconnected-(J6-Pad38)")
			(pintype "passive+no_connect")
		)
		(pad "39" smd roundrect
			(at 6.749 -2.15 90)
			(size 0.3 1.2)
			(layers "F.Cu" "F.Mask" "F.Paste")
			(roundrect_rratio 0.25)
			(net 119 "/Connectors/SDA_CAM0")
			(pintype "passive")
		)
		(pad "40" smd roundrect
			(at 7.249 -2.15 90)
			(size 0.3 1.2)
			(layers "F.Cu" "F.Mask" "F.Paste")
			(roundrect_rratio 0.25)
			(net 120 "/Connectors/SCL_CAM0")
			(pintype "passive")
		)
		(pad "41" smd roundrect
			(at 7.749 -2.15 90)
			(size 0.3 1.2)
			(layers "F.Cu" "F.Mask" "F.Paste")
			(roundrect_rratio 0.25)
			(net 42 "/Connectors/SDA_CAM1")
			(pintype "passive")
		)
		(pad "42" smd roundrect
			(at 8.249 -2.15 90)
			(size 0.3 1.2)
			(layers "F.Cu" "F.Mask" "F.Paste")
			(roundrect_rratio 0.25)
			(net 43 "/Connectors/SCL_CAM1")
			(pintype "passive")
		)
		(pad "43" smd roundrect
			(at 8.749 -2.15 90)
			(size 0.3 1.2)
			(layers "F.Cu" "F.Mask" "F.Paste")
			(roundrect_rratio 0.25)
			(net 46 "unconnected-(J6-Pad43)")
			(pintype "passive+no_connect")
		)
		(pad "44" smd roundrect
			(at 9.249 -2.15 90)
			(size 0.3 1.2)
			(layers "F.Cu" "F.Mask" "F.Paste")
			(roundrect_rratio 0.25)
			(net 47 "unconnected-(J6-Pad44)")
			(pintype "passive+no_connect")
		)
		(pad "45" smd roundrect
			(at 9.749 -2.15 90)
			(size 0.3 1.2)
			(layers "F.Cu" "F.Mask" "F.Paste")
			(roundrect_rratio 0.25)
			(net 48 "unconnected-(J6-Pad45)")
			(pintype "passive+no_connect")
		)
		(pad "46" smd roundrect
			(at 10.249 -2.15 90)
			(size 0.3 1.2)
			(layers "F.Cu" "F.Mask" "F.Paste")
			(roundrect_rratio 0.25)
			(net 49 "unconnected-(J6-Pad46)")
			(pintype "passive+no_connect")
		)
		(pad "47" smd roundrect
			(at 10.749 -2.15 90)
			(size 0.3 1.2)
			(layers "F.Cu" "F.Mask" "F.Paste")
			(roundrect_rratio 0.25)
			(net 50 "/Connectors/FFC_3V3")
			(pintype "passive")
		)
		(pad "48" smd roundrect
			(at 11.249 -2.15 90)
			(size 0.3 1.2)
			(layers "F.Cu" "F.Mask" "F.Paste")
			(roundrect_rratio 0.25)
			(net 50 "/Connectors/FFC_3V3")
			(pintype "passive")
		)
		(pad "49" smd roundrect
			(at 11.749 -2.15 90)
			(size 0.3 1.2)
			(layers "F.Cu" "F.Mask" "F.Paste")
			(roundrect_rratio 0.25)
			(net 113 "/Connectors/FFC_5V")
			(pintype "passive")
		)
		(pad "50" smd roundrect
			(at 12.249 -2.15 90)
			(size 0.3 1.2)
			(layers "F.Cu" "F.Mask" "F.Paste")
			(roundrect_rratio 0.25)
			(net 113 "/Connectors/FFC_5V")
			(pintype "passive")
		)
		(pad "MP1" smd roundrect
			(at -14.198 -0.3 90)
			(size 2.7 3)
			(layers "F.Cu" "F.Mask" "F.Paste")
			(roundrect_rratio 0.05)
			(net 1 "GND")
			(pinfunction "MP")
			(pintype "passive")
		)
		(pad "MP2" smd roundrect
			(at 14.198 -0.3 90)
			(size 2.7 3)
			(layers "F.Cu" "F.Mask" "F.Paste")
			(roundrect_rratio 0.05)
			(net 1 "GND")
			(pinfunction "MP")
			(pintype "passive")
		)
	)
	(footprint "antmicro-footprints:C_0603_1608Metric"
		(layer "F.Cu")
		(at 131.725 95.618 -90)
		(descr "Capacitor SMD 0603")
		(tags "capacitor 0603")
		(property "Reference" "C17"
			(at -1.638 0.915 90)
			(layer "F.SilkS")
			(effects
				(font
					(size 0.7 0.7)
					(thickness 0.15)
				)
				(justify right bottom)
			)
		)
		(property "Value" "C_10u_25V_0603"
			(at -1.42757 1.770288 90)
			(layer "F.Fab")
			(effects
				(font
					(size 0.7 0.7)
					(thickness 0.15)
				)
				(justify right bottom)
			)
		)
		(property "Datasheet" "https://product.tdk.com/en/search/capacitor/ceramic/mlcc/info?part_no=C1608X5R1E106M080AC"
			(at 0 0 270)
			(layer "F.Fab")
			(hide yes)
			(effects
				(font
					(size 1.27 1.27)
					(thickness 0.15)
				)
			)
		)
		(property "Description" "SMD Multilayer Ceramic Capacitor, 10 µF, 25 V, 0603 [1608 Metric], ± 20%, X5R, C"
			(at 0 0 270)
			(layer "F.Fab")
			(hide yes)
			(effects
				(font
					(size 1.27 1.27)
					(thickness 0.15)
				)
			)
		)
		(property "Author" "Antmicro"
			(at 36.107 227.343 0)
			(layer "F.Fab")
			(hide yes)
			(effects
				(font
					(size 1 1)
					(thickness 0.15)
				)
			)
		)
		(property "Dielectric" ""
			(at 36.107 227.343 0)
			(layer "F.Fab")
			(hide yes)
			(effects
				(font
					(size 1 1)
					(thickness 0.15)
				)
			)
		)
		(property "License" "Apache-2.0"
			(at 36.107 227.343 0)
			(layer "F.Fab")
			(hide yes)
			(effects
				(font
					(size 1 1)
					(thickness 0.15)
				)
			)
		)
		(property "MPN" "C1608X5R1E106M080AC"
			(at 36.107 227.343 0)
			(layer "F.Fab")
			(hide yes)
			(effects
				(font
					(size 1 1)
					(thickness 0.15)
				)
			)
		)
		(property "Manufacturer" "TDK"
			(at 36.107 227.343 0)
			(layer "F.Fab")
			(hide yes)
			(effects
				(font
					(size 1 1)
					(thickness 0.15)
				)
			)
		)
		(property "Val" "10u"
			(at 36.107 227.343 0)
			(layer "F.Fab")
			(hide yes)
			(effects
				(font
					(size 1 1)
					(thickness 0.15)
				)
			)
		)
		(property "Voltage" "25V"
			(at 36.107 227.343 0)
			(layer "F.Fab")
			(hide yes)
			(effects
				(font
					(size 1 1)
					(thickness 0.15)
				)
			)
		)
		(sheetname "/Power/")
		(sheetfile "power.kicad_sch")
		(attr smd)
		(fp_line
			(start -0.15 0.4)
			(end 0.15 0.4)
			(stroke
				(width 0.15)
				(type solid)
			)
			(layer "F.SilkS")
		)
		(fp_line
			(start -0.15 -0.4)
			(end 0.15 -0.4)
			(stroke
				(width 0.15)
				(type solid)
			)
			(layer "F.SilkS")
		)
		(fp_rect
			(start -1.25 -0.65)
			(end 1.25 0.65)
			(stroke
				(width 0.05)
				(type solid)
			)
			(fill no)
			(layer "F.CrtYd")
		)
		(fp_rect
			(start -0.8 -0.4)
			(end 0.8 0.4)
			(stroke
				(width 0.15)
				(type solid)
			)
			(fill no)
			(layer "F.Fab")
		)
		(pad "1" smd roundrect
			(at -0.7 0 270)
			(size 0.8 1)
			(layers "F.Cu" "F.Mask" "F.Paste")
			(roundrect_rratio 0.2)
			(net 1 "GND")
			(pintype "passive")
		)
		(pad "2" smd roundrect
			(at 0.7 0 270)
			(size 0.8 1)
			(layers "F.Cu" "F.Mask" "F.Paste")
			(roundrect_rratio 0.2)
			(net 4 "+12V")
			(pintype "passive")
		)
	)
)
